FILE_TYPE = CONNECTIVITY;
{Allegro Design Entry HDL 17.2-2016 S081 (4005846) 1/11/2022}
"PAGE_NUMBER" = 213;
0"NC";
1"P3V3_AUX\g";
2"P3V3_AUX\g";
3"P3V3_AUX\g";
4"P3V3_AUX\g";
5"P3V3_AUX\g";
6"P3V3_AUX\g"VOLTAGE"3.3";
7"P3V3_AUX\g";
8"GND\g";
9"GND\g";
10"GND\g";
11"GND\g";
12"GND\g";
13"GND\g";
14"GND\g";
15"FM_AC_PWR_BTN_R_N"CDS_PHYS_NET_NAME"TP_SPI_TPM_CLK";
16"PWRGD_PS_PWROK_PLD";
17"FM_AC_PWR_BTN_PLD_ISO_N"CDS_PHYS_NET_NAME"TP_SPI_TPM_CLK";
18"FM_AC_PWR_BTN_PLD_ISO_R_N"CDS_PHYS_NET_NAME"TP_SPI_TPM_CLK";
19"NC_UXX_2Y"CDS_PHYS_NET_NAME"TP_SPI_TPM_CLK";
20"FM_AC_PWR_BTN_PLD_N"CDS_PHYS_NET_NAME"TP_SPI_TPM_CLK";
21"PWRGD_PS_PWROK_PLD_N";
22"FM_PS_EN_PLD_BUF1";
23"NC_U150_B1";
24"PWRGD_PS_PWROK_PLD_ISO_R";
25"FM_PS_EN_PLD_R";
26"NC_U150_A1";
27"PWRGD_PS_PWROK_PLD_ISO";
%"UNIVERSAL_GND"
"1","(-8275,1975)","0","logical_power","I17";
;
CDS_LIB"logical_power"
HDL_POWER"GND";
"A"11;
%"Q_RES"
"2","(-8275,2950)","0","pure_quanta","I18";
;
PART_NUMBER"CS24702JB10"
PACK_TYPE"0402LF"
TOLERANCE"5%"
WATTAGE"1/16W"
VALUE"4.7K"
MATERIAL"CHIP"
$LOCATION"R4604"
CDS_LIB"pure_quanta"
CDS_LOCATION"R4604"
$SEC"1"
CDS_SEC"1";
"A"
$PN"1"3;
"B"
$PN"2"21;
%"UNIVERSAL_POWER"
"1","(-8275,3175)","0","logical_power","I19";
;
HDL_POWER"P3V3_AUX"
CDS_LIB"logical_power";
"A"3;
%"74LVC2G17GW"
"1","(-8000,4825)","0","pure_quanta","I2";
;
PART_NUMBER"AL2G0017005"
MATERIAL"IC"
VALUE"74LVC2G17GW"
PART_TYPE"SMLF"
$LOCATION"U150"
CDS_LIB"pure_quanta"
CDS_LMAN_SYM_OUTLINE"-225,275,225,-275"
NEEDS_NO_SIZE"TRUE"
CDS_LOCATION"U150"
$SEC"1"
CDS_SEC"1";
"B0"
$PN"6"22;
"A1"
$PN"3"26;
"A0"
$PN"1"25;
"GND"
$PN"2"13;
"B1"
$PN"4"23;
"VCC"
$PN"5"6;
%"UNIVERSAL_GND"
"1","(-7125,2275)","0","logical_power","I20";
;
HDL_POWER"GND"
CDS_LIB"logical_power";
"A"12;
%"MOSFET_NCH_DUAL"
"2","(-7175,2650)","0","pure_quanta","I21";
;
PART_NUMBER"BAM138K0003"
PART_TYPE"SMLF"
MATERIAL"IC"
VALUE"PJT138K"
$LOCATION"Q144"
CDS_LIB"pure_quanta"
NEEDS_NO_SIZE"TRUE"
CDS_LMAN_SYM_OUTLINE"-150,150,150,-150"
CDS_LOCATION"Q144"
$SEC"2"
CDS_SEC"2";
"S2"
$PN"4"12;
"G2"
$PN"5"21;
"D2"
$PN"3"27;
%"Q_RES"
"2","(-7125,3075)","0","pure_quanta","I22";
;
PART_NUMBER"CS24702JB10"
MATERIAL"CHIP"
PACK_TYPE"0402LF"
WATTAGE"1/16W"
TOLERANCE"5%"
VALUE"4.7K"
$LOCATION"R4605"
CDS_LIB"pure_quanta"
CDS_LOCATION"R4605"
$SEC"1"
CDS_SEC"1";
"A"
$PN"1"5;
"B"
$PN"2"27;
%"UNIVERSAL_POWER"
"1","(-7125,3300)","0","logical_power","I23";
;
HDL_POWER"P3V3_AUX"
CDS_LIB"logical_power";
"A"5;
%"MOSFET_NCH_DUAL"
"1","(-8325,2350)","0","pure_quanta","I27";
;
PART_NUMBER"BAM138K0003"
PART_TYPE"SMLF"
VALUE"PJT138K"
MATERIAL"IC"
LOCATION"Q144"
CDS_LIB"pure_quanta"
NEEDS_NO_SIZE"TRUE"
CDS_LMAN_SYM_OUTLINE"-150,150,150,-150"
$SEC"1"
CDS_SEC"1";
"D1"
$PN"6"21;
"G1"
$PN"2"16;
"S1"
$PN"1"11;
%"Q_RES"
"1","(-5850,2900)","0","pure_quanta","I29";
;
PART_NUMBER"CS03322FB03"
VALUE"33.2"
TOLERANCE"1%"
MATERIAL"CHIP"
WATTAGE"1/16W"
PACK_TYPE"0402LF"
$LOCATION"R1446"
CDS_LIB"pure_quanta"
CDS_LOCATION"R1446"
$SEC"1"
CDS_SEC"1";
"B"
$PN"2"24;
"A"
$PN"1"27;
%"UNIVERSAL_GND"
"1","(-7975,4250)","0","logical_power","I3";
;
HDL_POWER"GND"
CDS_LIB"logical_power";
"A"13;
%"UNIVERSAL_POWER"
"1","(-5300,1625)","0","logical_power","I31";
;
HDL_POWER"P3V3_AUX"
CDS_LIB"logical_power";
"A"2;
%"Q_RES"
"2","(-5300,1375)","0","pure_quanta","I32";
;
PART_NUMBER"CS31002FB08"
MATERIAL"CHIP"
PACK_TYPE"0402LF"
TOLERANCE"1%"
VALUE"10K"
WATTAGE"1/16W"
$LOCATION"R4719"
CDS_LIB"pure_quanta"
CDS_LOCATION"R4719"
$SEC"1"
CDS_SEC"1";
"A"
$PN"1"2;
"B"
$PN"2"17;
%"Q_RES"
"1","(-5800,1050)","0","pure_quanta","I33";
;
PART_NUMBER"CS03322FB03"
TOLERANCE"1%"
MATERIAL"EMPTY"
VALUE"33.2"
$LOCATION"R4718"
WATTAGE"1/16W"
PACK_TYPE"0402LF"
CDS_LIB"pure_quanta"
CDS_LOCATION"R4718"
$SEC"1"
CDS_SEC"1";
"B"
$PN"2"17;
"A"
$PN"1"18;
%"UNIVERSAL_GND"
"1","(-6700,1200)","0","logical_power","I34";
;
HDL_POWER"GND"
CDS_LIB"logical_power";
"A"9;
%"Q_CAP"
"1","(-6700,1375)","0","pure_quanta","I35";
;
PART_NUMBER"CH4104K1B00"
VALUE"0.1UF"
VOLTAGE"25V"
PACK_TYPE"0402"
TOLERANCE"10%"
MATERIAL"EMPTY"
$LOCATION"C2370"
CDS_LIB"pure_quanta"
CDS_LOCATION"C2370"
$SEC"1"
CDS_SEC"1";
"B"
$PN"2"9;
"A"
$PN"1"4;
%"UNIVERSAL_POWER"
"1","(-6825,1600)","0","logical_power","I36";
;
HDL_POWER"P3V3_AUX"
CDS_LIB"logical_power";
"A"4;
%"74LVC2G07DW7"
"1","(-7250,1000)","0","pure_quanta","I37";
;
PART_NUMBER"AL002G07003"
PART_TYPE"SMLF"
MATERIAL"EMPTY"
VALUE"74LVC2G07DW-7"
$LOCATION"U332"
CDS_LIB"pure_quanta"
CDS_LMAN_SYM_OUTLINE"-175,100,175,-100"
NEEDS_NO_SIZE"TRUE"
CDS_LOCATION"U332"
$SEC"1"
CDS_SEC"1";
"VCC"
$PN"5"4;
"GND"
$PN"2"10;
"2Y"
$PN"4"19;
"1Y"
$PN"6"18;
"2A"
$PN"3"10;
"1A"
$PN"1"20;
%"UNIVERSAL_GND"
"1","(-7675,750)","0","logical_power","I38";
;
CDS_LIB"logical_power"
HDL_POWER"GND";
"A"10;
%"UNIVERSAL_POWER"
"1","(-8850,1625)","0","logical_power","I39";
;
HDL_POWER"P3V3_AUX"
CDS_LIB"logical_power";
"A"1;
%"UNIVERSAL_GND"
"1","(-7775,5275)","0","logical_power","I4";
;
HDL_POWER"GND"
CDS_LIB"logical_power";
"A"14;
%"Q_RES"
"2","(-8850,1375)","0","pure_quanta","I40";
;
PART_NUMBER"CS28452FB06"
PACK_TYPE"0402LF"
VALUE"8.45K"
WATTAGE"1/16W"
TOLERANCE"1%"
MATERIAL"EMPTY"
$LOCATION"R4716"
CDS_LIB"pure_quanta"
CDS_LOCATION"R4716"
$SEC"1"
CDS_SEC"1";
"A"
$PN"1"1;
"B"
$PN"2"15;
%"Q_RES"
"1","(-8650,1050)","0","pure_quanta","I41";
;
PART_NUMBER"CS00002JB13"
TOLERANCE"5%"
VALUE"0"
MATERIAL"EMPTY"
$LOCATION"R4717"
WATTAGE"1/16W"
PACK_TYPE"0402LF"
CDS_LIB"pure_quanta"
CDS_LOCATION"R4717"
$SEC"1"
CDS_SEC"1";
"B"
$PN"2"20;
"A"
$PN"1"15;
%"Q_CAP"
"1","(-8825,850)","2","pure_quanta","I42";
;
PART_NUMBER"CH5104KEB02"
TOLERANCE"10%"
VALUE"1UF"
VOLTAGE"25V"
PACK_TYPE"C0402"
MATERIAL"EMPTY"
$LOCATION"C2369"
CDS_LIB"pure_quanta"
CDS_LOCATION"C2369"
$SEC"1"
CDS_SEC"1";
"B"
$PN"2"8;
"A"
$PN"1"15;
%"UNIVERSAL_GND"
"1","(-8825,650)","0","logical_power","I43";
;
HDL_POWER"GND"
CDS_LIB"logical_power";
"A"8;
%"Q_CAP"
"1","(-7775,5475)","0","pure_quanta","I5";
;
PART_NUMBER"CH4104K1B00"
PACK_TYPE"0402"
VALUE"0.1UF"
VOLTAGE"25V"
MATERIAL"X7R"
TOLERANCE"10%"
$LOCATION"C1619"
CDS_LIB"pure_quanta"
CDS_LOCATION"C1619"
$SEC"1"
CDS_SEC"1";
"B"
$PN"2"14;
"A"
$PN"1"6;
%"UNIVERSAL_POWER"
"1","(-7775,5750)","0","logical_power","I6";
;
HDL_POWER"P3V3_AUX"
CDS_LIB"logical_power";
"A"6;
%"Q_RES"
"2","(-6225,5250)","2","pure_quanta","I7";
;
PART_NUMBER"CS24702JB10"
PACK_TYPE"0402LF"
VALUE"4.7K"
MATERIAL"EMPTY"
WATTAGE"1/16W"
TOLERANCE"5%"
$LOCATION"R2355"
CDS_LIB"pure_quanta"
CDS_LOCATION"R2355"
$SEC"1"
CDS_SEC"1";
"A"
$PN"1"7;
"B"
$PN"2"22;
%"UNIVERSAL_POWER"
"1","(-6225,5450)","0","logical_power","I8";
;
HDL_POWER"P3V3_AUX"
CDS_LIB"logical_power";
"A"7;
END.
